# T6G (Grand Teton) — schematic netlist excerpt (pin names and nets, part order shuffled) for the footprints in the layout excerpt that follows; sources: Cadence DE-HDL packaged netlist, KiCad conversion of 04192023_DAF0TMB3IC0_F0TG_MB_C_brd_V02_OCP.brd

R2704  Q_RES  0 5% CHIP  pkg 0402LF  page 250 : A = SMB_BMC_SWB_SDA_R4 ; B = SMB_BMC_SWB_SDA
PC6534  Q_CAP  150PF 50V 5% NPO  pkg 0402  page 361 : A = P1V8_RETIMER_CPU1_FB ; B = P1V8_CPU1_RT_1D
C6642  Q_CAP_DIFFBUS  DIFF BUS_0.22UF 6.3V 20% X6S  pkg C0201  page 319 : \1\ = P5E_CPU1_P0_TX_BUF_C_DN<6> ; \2\ = P5E_CPU1_P0_TX_BUF_DN<6>

(kicad_pcb
	(version 20260206)
	(generator "pcbnew")
	(generator_version "10.0")
	(general
		(thickness 1.6)
		(legacy_teardrops no)
	)
	(paper "A4")
	(title_block
		(title "04192023_DAF0TMB3IC0_F0TG_MB_C_brd_V02_OCP.brd")
		(comment 1 "Grand Teton / footprints 1615-1617 of 8354")
	)
	(layers
		(0 "F.Cu" signal "TOP")
		(4 "In1.Cu" signal "GND")
		(6 "In2.Cu" signal "IN1")
		(8 "In3.Cu" signal "GND1")
		(10 "In4.Cu" signal "IN2")
		(12 "In5.Cu" signal "GND2")
		(14 "In6.Cu" signal "IN3")
		(16 "In7.Cu" signal "GND3")
		(18 "In8.Cu" signal "VCC")
		(20 "In9.Cu" signal "VCC1")
		(22 "In10.Cu" signal "GND4")
		(24 "In11.Cu" signal "IN4")
		(26 "In12.Cu" signal "GND5")
		(28 "In13.Cu" signal "IN5")
		(30 "In14.Cu" signal "GND6")
		(32 "In15.Cu" signal "IN6")
		(34 "In16.Cu" signal "GND7")
		(2 "B.Cu" signal "BOTTOM")
		(9 "F.Adhes" user "F.Adhesive")
		(11 "B.Adhes" user "B.Adhesive")
		(13 "F.Paste" user "Package Geometry/Pastemask Top")
		(15 "B.Paste" user "Package Geometry/Pastemask Bottom")
		(5 "F.SilkS" user "Ref Des/Silkscreen Top")
		(7 "B.SilkS" user "Ref Des/Silkscreen Bottom")
		(1 "F.Mask" user "Board Geometry/Soldermask Top")
		(3 "B.Mask" user "Board Geometry/Soldermask Bottom")
		(17 "Dwgs.User" user "User.Drawings")
		(19 "Cmts.User" user "User.Comments")
		(21 "Eco1.User" user "User.Eco1")
		(23 "Eco2.User" user "User.Eco2")
		(25 "Edge.Cuts" user "Board Geometry/Outline")
		(27 "Margin" user)
		(31 "F.CrtYd" user "Package Geometry/Place Bound Top")
		(29 "B.CrtYd" user "Package Geometry/Place Bound Bottom")
		(35 "F.Fab" user "Ref Des/Assembly Top")
		(33 "B.Fab" user "Ref Des/Assembly Bottom")
	)
	(footprint ""
		(layer "F.Cu")
		(at 294.421052 -114.221514)
		(property "Reference" "R2704"
			(at 0 0 0)
			(layer "F.SilkS")
			(hide yes)
			(effects
				(font
					(size 1.27 1.27)
				)
			)
		)
		(property "Value" ""
			(at 0 0 0)
			(layer "F.Fab")
			(effects
				(font
					(size 1.27 1.27)
				)
			)
		)
		(duplicate_pad_numbers_are_jumpers no)
		(fp_line
			(start -0.7874 -0.4064)
			(end 0.7874 -0.4064)
			(stroke
				(width 0.1524)
				(type default)
			)
			(layer "F.SilkS")
		)
		(fp_line
			(start -0.7874 0.4064)
			(end -0.7874 -0.4064)
			(stroke
				(width 0.1524)
				(type default)
			)
			(layer "F.SilkS")
		)
		(fp_line
			(start 0.7874 -0.4064)
			(end 0.7874 0.4064)
			(stroke
				(width 0.1524)
				(type default)
			)
			(layer "F.SilkS")
		)
		(fp_line
			(start 0.7874 0.4064)
			(end -0.7874 0.4064)
			(stroke
				(width 0.1524)
				(type default)
			)
			(layer "F.SilkS")
		)
		(fp_line
			(start -0.67945 -0.305054)
			(end -0.12065 -0.305054)
			(stroke
				(width 0.1)
				(type default)
			)
			(layer "F.Fab")
		)
		(fp_line
			(start -0.67945 0.3048)
			(end -0.67945 -0.305054)
			(stroke
				(width 0.1)
				(type default)
			)
			(layer "F.Fab")
		)
		(fp_line
			(start -0.12065 -0.305054)
			(end -0.12065 -0.2794)
			(stroke
				(width 0.1)
				(type default)
			)
			(layer "F.Fab")
		)
		(fp_line
			(start -0.12065 -0.2794)
			(end 0.12065 -0.2794)
			(stroke
				(width 0.1)
				(type default)
			)
			(layer "F.Fab")
		)
		(fp_line
			(start -0.12065 0.2794)
			(end -0.12065 0.3048)
			(stroke
				(width 0.1)
				(type default)
			)
			(layer "F.Fab")
		)
		(fp_line
			(start -0.12065 0.3048)
			(end -0.67945 0.3048)
			(stroke
				(width 0.1)
				(type default)
			)
			(layer "F.Fab")
		)
		(fp_line
			(start 0.120396 0.2794)
			(end -0.12065 0.2794)
			(stroke
				(width 0.1)
				(type default)
			)
			(layer "F.Fab")
		)
		(fp_line
			(start 0.120396 0.3048)
			(end 0.120396 0.2794)
			(stroke
				(width 0.1)
				(type default)
			)
			(layer "F.Fab")
		)
		(fp_line
			(start 0.12065 -0.3048)
			(end 0.67945 -0.3048)
			(stroke
				(width 0.1)
				(type default)
			)
			(layer "F.Fab")
		)
		(fp_line
			(start 0.12065 -0.2794)
			(end 0.12065 -0.3048)
			(stroke
				(width 0.1)
				(type default)
			)
			(layer "F.Fab")
		)
		(fp_line
			(start 0.67945 -0.3048)
			(end 0.67945 0.3048)
			(stroke
				(width 0.1)
				(type default)
			)
			(layer "F.Fab")
		)
		(fp_line
			(start 0.67945 0.3048)
			(end 0.120396 0.3048)
			(stroke
				(width 0.1)
				(type default)
			)
			(layer "F.Fab")
		)
		(pad "1" smd circle
			(at -0.40005 0)
			(size 0 0)
			(layers "F.Cu" "F.Mask" "F.Paste")
			(net "SMB_BMC_SWB_SDA_R4")
		)
		(pad "2" smd circle
			(at 0.40005 0)
			(size 0 0)
			(layers "F.Cu" "F.Mask" "F.Paste")
			(net "SMB_BMC_SWB_SDA")
		)
	)
	(footprint ""
		(layer "F.Cu")
		(at 66.148204 -408.517344 -90)
		(property "Reference" "C6642"
			(at 0 0 270)
			(layer "F.SilkS")
			(hide yes)
			(effects
				(font
					(size 1.27 1.27)
				)
			)
		)
		(property "Value" ""
			(at 0 0 270)
			(layer "F.Fab")
			(effects
				(font
					(size 1.27 1.27)
				)
			)
		)
		(duplicate_pad_numbers_are_jumpers no)
		(fp_line
			(start -0.299974 0.150114)
			(end -0.299974 -0.150114)
			(stroke
				(width 0.1)
				(type default)
			)
			(layer "F.Fab")
		)
		(fp_line
			(start 0.299974 0.150114)
			(end -0.299974 0.150114)
			(stroke
				(width 0.1)
				(type default)
			)
			(layer "F.Fab")
		)
		(fp_line
			(start -0.299974 -0.150114)
			(end 0.299974 -0.150114)
			(stroke
				(width 0.1)
				(type default)
			)
			(layer "F.Fab")
		)
		(fp_line
			(start 0.299974 -0.150114)
			(end 0.299974 0.150114)
			(stroke
				(width 0.1)
				(type default)
			)
			(layer "F.Fab")
		)
		(pad "1" smd rect
			(at -0.2667 0 270)
			(size 0.3048 0.381)
			(layers "F.Cu" "F.Mask" "F.Paste")
			(net "P5E_CPU1_P0_TX_BUF_C_DN<6>")
		)
		(pad "2" smd rect
			(at 0.2667 0 270)
			(size 0.3048 0.381)
			(layers "F.Cu" "F.Mask" "F.Paste")
			(net "P5E_CPU1_P0_TX_BUF_DN<6>")
		)
	)
	(footprint ""
		(layer "F.Cu")
		(at 225.899472 -290.341812 90)
		(property "Reference" "PC6534"
			(at 0 0 90)
			(layer "F.SilkS")
			(hide yes)
			(effects
				(font
					(size 1.27 1.27)
				)
			)
		)
		(property "Value" ""
			(at 0 0 90)
			(layer "F.Fab")
			(effects
				(font
					(size 1.27 1.27)
				)
			)
		)
		(duplicate_pad_numbers_are_jumpers no)
		(fp_line
			(start 0.7874 -0.4064)
			(end 0.7874 0.4064)
			(stroke
				(width 0.1524)
				(type default)
			)
			(layer "F.SilkS")
		)
		(fp_line
			(start -0.7874 -0.4064)
			(end 0.7874 -0.4064)
			(stroke
				(width 0.1524)
				(type default)
			)
			(layer "F.SilkS")
		)
		(fp_line
			(start 0.7874 0.4064)
			(end -0.7874 0.4064)
			(stroke
				(width 0.1524)
				(type default)
			)
			(layer "F.SilkS")
		)
		(fp_line
			(start -0.7874 0.4064)
			(end -0.7874 -0.4064)
			(stroke
				(width 0.1524)
				(type default)
			)
			(layer "F.SilkS")
		)
		(fp_line
			(start -0.12065 -0.305054)
			(end -0.12065 -0.2794)
			(stroke
				(width 0.1)
				(type default)
			)
			(layer "F.Fab")
		)
		(fp_line
			(start -0.67945 -0.305054)
			(end -0.12065 -0.305054)
			(stroke
				(width 0.1)
				(type default)
			)
			(layer "F.Fab")
		)
		(fp_line
			(start 0.67945 -0.3048)
			(end 0.67945 0.3048)
			(stroke
				(width 0.1)
				(type default)
			)
			(layer "F.Fab")
		)
		(fp_line
			(start 0.12065 -0.3048)
			(end 0.67945 -0.3048)
			(stroke
				(width 0.1)
				(type default)
			)
			(layer "F.Fab")
		)
		(fp_line
			(start 0.12065 -0.2794)
			(end 0.12065 -0.3048)
			(stroke
				(width 0.1)
				(type default)
			)
			(layer "F.Fab")
		)
		(fp_line
			(start -0.12065 -0.2794)
			(end 0.12065 -0.2794)
			(stroke
				(width 0.1)
				(type default)
			)
			(layer "F.Fab")
		)
		(fp_line
			(start 0.120396 0.2794)
			(end -0.12065 0.2794)
			(stroke
				(width 0.1)
				(type default)
			)
			(layer "F.Fab")
		)
		(fp_line
			(start -0.12065 0.2794)
			(end -0.12065 0.3048)
			(stroke
				(width 0.1)
				(type default)
			)
			(layer "F.Fab")
		)
		(fp_line
			(start 0.67945 0.3048)
			(end 0.120396 0.3048)
			(stroke
				(width 0.1)
				(type default)
			)
			(layer "F.Fab")
		)
		(fp_line
			(start 0.120396 0.3048)
			(end 0.120396 0.2794)
			(stroke
				(width 0.1)
				(type default)
			)
			(layer "F.Fab")
		)
		(fp_line
			(start -0.12065 0.3048)
			(end -0.67945 0.3048)
			(stroke
				(width 0.1)
				(type default)
			)
			(layer "F.Fab")
		)
		(fp_line
			(start -0.67945 0.3048)
			(end -0.67945 -0.305054)
			(stroke
				(width 0.1)
				(type default)
			)
			(layer "F.Fab")
		)
		(pad "1" smd circle
			(at -0.40005 0 90)
			(size 0 0)
			(layers "F.Cu" "F.Mask" "F.Paste")
			(net "P1V8_RETIMER_CPU1_FB")
		)
		(pad "2" smd circle
			(at 0.40005 0 90)
			(size 0 0)
			(layers "F.Cu" "F.Mask" "F.Paste")
			(net "P1V8_CPU1_RT_1D")
		)
	)
)
